(kicad_pcb
	(version 20221018)
	(generator pcbnew)
	(general
    (thickness 1.7403)
  )
	(paper "A4")
	(title_block
    (title "Data Center RDIMM DDR4 Tester")
    (date "2024-09-30")
    (rev "1.2.4")
		(comment 9 "footprints 550-557 of 690")
	)
	(layers
    (0 "F.Cu" signal)
    (1 "In1.Cu" power)
    (2 "In2.Cu" signal)
    (3 "In3.Cu" power)
    (4 "In4.Cu" power)
    (5 "In5.Cu" signal)
    (6 "In6.Cu" power)
    (7 "In7.Cu" signal)
    (8 "In8.Cu" power)
    (9 "In9.Cu" signal)
    (10 "In10.Cu" power)
    (31 "B.Cu" signal)
    (32 "B.Adhes" user "B.Adhesive")
    (33 "F.Adhes" user "F.Adhesive")
    (34 "B.Paste" user)
    (35 "F.Paste" user)
    (36 "B.SilkS" user "B.Silkscreen")
    (37 "F.SilkS" user "F.Silkscreen")
    (38 "B.Mask" user)
    (39 "F.Mask" user)
    (40 "Dwgs.User" user "User.Drawings")
    (41 "Cmts.User" user "User.Comments")
    (42 "Eco1.User" user "User.Eco1")
    (43 "Eco2.User" user "User.Eco2")
    (44 "Edge.Cuts" user)
    (45 "Margin" user)
    (46 "B.CrtYd" user "B.Courtyard")
    (47 "F.CrtYd" user "F.Courtyard")
    (48 "B.Fab" user)
    (49 "F.Fab" user)
  )
	(footprint "data-center-rdimm-ddr4-tester-footprints:C_0201" (layer "B.Cu")
    (at 173.225 91.225 -90)
    (descr "Capacitor SMD 0201")
    (tags "capacitor SMD 0201")
    (property "Author" "Antmicro")
    (property "Dielectric" "")
    (property "License" "Apache-2.0")
    (property "MPN" "CC0201KRX6S5BB104")
    (property "Manufacturer" "Yaego")
    (property "Sheetfile" "fpga-power.kicad_sch")
    (property "Sheetname" "FPGA power")
    (property "Val" "100n")
    (property "Voltage" "")
    (property "ki_description" " ")
    (attr smd)
    (fp_text reference "C279" (at -1.505 0.525 90) (layer "B.SilkS")
        (effects (font (size 0.7 0.7) (thickness 0.15)) (justify left bottom mirror))
    )
    (fp_text value "C_100n_0201" (at 0 -1.4 90) (layer "B.Fab") hide
        (effects (font (size 0.7 0.7) (thickness 0.15)) (justify left bottom mirror))
    )
    (fp_text user "Author: Antmicro" (at -0.72 -5.4 90) (layer "B.Fab") hide
        (effects (font (size 0.7 0.7) (thickness 0.15)) (justify left bottom mirror))
    )
    (fp_text user "License: Apache-2.0" (at -0.72 -4.4 90) (layer "B.Fab") hide
        (effects (font (size 0.7 0.7) (thickness 0.15)) (justify left bottom mirror))
    )
    (fp_text user "${REFERENCE}" (at -0.72 -3.4 90) (layer "B.Fab") hide
        (effects (font (size 0.7 0.7) (thickness 0.15)) (justify left bottom mirror))
    )
    (fp_rect (start -0.72 0.38) (end 0.72 -0.38)
      (stroke (width 0.05) (type solid)) (fill none) (layer "B.CrtYd"))
    (fp_rect (start 0.3 -0.15) (end -0.301 0.149)
      (stroke (width 0.15) (type solid)) (fill none) (layer "B.Fab"))
    (pad "" smd roundrect (at -0.349 0.002 270) (size 0.318 0.36) (layers "B.Paste") (roundrect_rratio 0.25))
    (pad "" smd roundrect (at 0.341 0.002 270) (size 0.318 0.36) (layers "B.Paste") (roundrect_rratio 0.25))
    (pad "1" smd roundrect (at -0.321 0.002 270) (size 0.46 0.4) (layers "B.Cu" "B.Mask") (roundrect_rratio 0.25)
      (net 77 "VDDQ") (pintype "passive"))
    (pad "2" smd roundrect (at 0.32 0.002 270) (size 0.46 0.4) (layers "B.Cu" "B.Mask") (roundrect_rratio 0.25)
      (net 9 "GND") (pintype "passive"))
  )
	(footprint "data-center-rdimm-ddr4-tester-footprints:DFN3538" (layer "B.Cu")
    (at 182.71 119.7 90)
    (property "Author" "Antmicro")
    (property "License" "Apache-2.0")
    (property "MPN" "CD-MMBL110S")
    (property "Manufacturer" "Bourns")
    (property "Sheetfile" "ethernet.kicad_sch")
    (property "Sheetname" "Ethernet")
    (property "ki_description" "Bridge Rectifiers 1000V 1A MMBL DFN3538")
    (attr smd)
    (fp_text reference "D12" (at 2.21 1.03 unlocked) (layer "B.SilkS")
        (effects (font (size 0.7 0.7) (thickness 0.15)) (justify left bottom mirror))
    )
    (fp_text value "CD-MMBL110S" (at 0 -3.5 270 unlocked) (layer "B.Fab") hide
        (effects (font (size 0.7 0.7) (thickness 0.15)) (justify left bottom mirror))
    )
    (fp_text user "~" (at -0.31 -2.59 270 unlocked) (layer "B.SilkS")
        (effects (font (size 0.7 0.7) (thickness 0.15)) (justify left bottom mirror))
    )
    (fp_text user "Author: Antmicro" (at -2.1 -5.599 270) (layer "B.Fab") hide
        (effects (font (size 0.7 0.7) (thickness 0.15)) (justify left bottom mirror))
    )
    (fp_text user "${REFERENCE}" (at -2.1 -4.599 270) (layer "B.Fab") hide
        (effects (font (size 0.7 0.7) (thickness 0.15)) (justify left bottom mirror))
    )
    (fp_text user "License: Apache-2.0" (at -2.1 -6.599 270) (layer "B.Fab") hide
        (effects (font (size 0.7 0.7) (thickness 0.15)) (justify left bottom mirror))
    )
    (fp_line (start -1.8 -2.05) (end -1.6 -2.05)
      (stroke (width 0.15) (type solid)) (layer "B.SilkS"))
    (fp_line (start -1.8 1.5) (end -1.8 -2.05)
      (stroke (width 0.15) (type solid)) (layer "B.SilkS"))
    (fp_line (start -0.95 -2.05) (end 0.95 -2.05)
      (stroke (width 0.15) (type solid)) (layer "B.SilkS"))
    (fp_line (start -0.95 2) (end 0.95 2)
      (stroke (width 0.15) (type solid)) (layer "B.SilkS"))
    (fp_line (start -0.902 2.25) (end -0.6 2.25)
      (stroke (width 0.15) (type solid)) (layer "B.SilkS"))
    (fp_line (start 0.748 2.452) (end 0.748 2.15)
      (stroke (width 0.15) (type solid)) (layer "B.SilkS"))
    (fp_line (start 0.9 2.301) (end 0.598 2.301)
      (stroke (width 0.15) (type solid)) (layer "B.SilkS"))
    (fp_line (start 1.6 -2.05) (end 1.8 -2.05)
      (stroke (width 0.15) (type solid)) (layer "B.SilkS"))
    (fp_line (start 1.6 2) (end 1.8 2)
      (stroke (width 0.15) (type solid)) (layer "B.SilkS"))
    (fp_line (start 1.8 2) (end 1.8 -2.05)
      (stroke (width 0.15) (type solid)) (layer "B.SilkS"))
    (fp_rect (start -2.1 2.6) (end 2.1 -2.6)
      (stroke (width 0.05) (type solid)) (fill none) (layer "B.CrtYd"))
    (fp_line (start -1.051 2) (end -1.801 1.25)
      (stroke (width 0.15) (type solid)) (layer "B.Fab"))
    (fp_rect (start 1.8 -2.048) (end -1.8 2)
      (stroke (width 0.15) (type solid)) (fill none) (layer "B.Fab"))
    (pad "1" smd roundrect (at -1.27 1.85) (size 1.4 0.48) (layers "B.Cu" "B.Paste" "B.Mask") (roundrect_rratio 0.25)
      (net 807 "/Ethernet/VSS_RAW") (pinfunction "1") (pintype "output"))
    (pad "2" smd roundrect (at 1.27 1.85) (size 1.4 0.48) (layers "B.Cu" "B.Paste" "B.Mask") (roundrect_rratio 0.25)
      (net 808 "/Ethernet/VDD_RAW") (pinfunction "2") (pintype "output"))
    (pad "3" smd roundrect (at -1.27 -1.85) (size 1.4 0.48) (layers "B.Cu" "B.Paste" "B.Mask") (roundrect_rratio 0.25)
      (net 606 "/Ethernet/PAIR_36") (pinfunction "3") (pintype "input"))
    (pad "4" smd roundrect (at 1.27 -1.85) (size 1.4 0.48) (layers "B.Cu" "B.Paste" "B.Mask") (roundrect_rratio 0.25)
      (net 605 "/Ethernet/PAIR_12") (pinfunction "4") (pintype "input"))
  )
	(footprint "data-center-rdimm-ddr4-tester-footprints:R_0402_1005Metric" (layer "B.Cu")
    (at 131.425 103.65 90)
    (descr "Resistor SMD 0402")
    (tags "resistor SMD 0402")
    (property "Author" "Antmicro")
    (property "License" "Apache-2.0")
    (property "MPN" "CR0402-FX-1002GLF")
    (property "Manufacturer" "Bourns")
    (property "Sheetfile" "supply.kicad_sch")
    (property "Sheetname" "Supply")
    (property "Tolerance" "1%")
    (property "Val" "10k")
    (property "ki_description" "10k resistor in 0402 package with 1% tolerance")
    (attr smd)
    (fp_text reference "R213" (at 1.75 1.255 270) (layer "B.SilkS")
        (effects (font (size 0.7 0.7) (thickness 0.15)) (justify left bottom mirror))
    )
    (fp_text value "R_10k_0402" (at 0 -1.4 270) (layer "B.Fab") hide
        (effects (font (size 0.7 0.7) (thickness 0.15)) (justify left bottom mirror))
    )
    (fp_text user "${REFERENCE}" (at -0.95 -3.168 270) (layer "B.Fab") hide
        (effects (font (size 0.7 0.7) (thickness 0.15)) (justify left bottom mirror))
    )
    (fp_text user "Author: Antmicro" (at -0.95 -4.169 270) (layer "B.Fab") hide
        (effects (font (size 0.7 0.7) (thickness 0.15)) (justify left bottom mirror))
    )
    (fp_text user "License: Apache-2.0" (at -0.95 -5.169 270) (layer "B.Fab") hide
        (effects (font (size 0.7 0.7) (thickness 0.15)) (justify left bottom mirror))
    )
    (fp_rect (start -0.93 0.47) (end 0.93 -0.47)
      (stroke (width 0.05) (type solid)) (fill none) (layer "B.CrtYd"))
    (fp_rect (start -0.5 0.25) (end 0.5 -0.25)
      (stroke (width 0.15) (type solid)) (fill none) (layer "B.Fab"))
    (pad "1" smd roundrect (at -0.485 0 90) (size 0.59 0.64) (layers "B.Cu" "B.Paste" "B.Mask") (roundrect_rratio 0.25)
      (net 790 "/Supply/PWR_SEQ_EN") (pintype "passive"))
    (pad "2" smd roundrect (at 0.485 0 90) (size 0.59 0.64) (layers "B.Cu" "B.Paste" "B.Mask") (roundrect_rratio 0.25)
      (net 9 "GND") (pintype "passive"))
  )
	(footprint "data-center-rdimm-ddr4-tester-footprints:R_0402_1005Metric" (layer "B.Cu")
    (at 228.55 122)
    (descr "Resistor SMD 0402")
    (tags "resistor SMD 0402")
    (property "Author" "Antmicro")
    (property "License" "Apache-2.0")
    (property "MPN" "CR0402-FX-1002GLF")
    (property "Manufacturer" "Bourns")
    (property "Sheetfile" "supply.kicad_sch")
    (property "Sheetname" "Supply")
    (property "Tolerance" "1%")
    (property "Val" "10k")
    (property "ki_description" "10k resistor in 0402 package with 1% tolerance")
    (attr smd)
    (fp_text reference "R218" (at 1.5 -1.52 180) (layer "B.SilkS")
        (effects (font (size 0.7 0.7) (thickness 0.15)) (justify left bottom mirror))
    )
    (fp_text value "R_10k_0402" (at 0 -1.4 180) (layer "B.Fab") hide
        (effects (font (size 0.7 0.7) (thickness 0.15)) (justify left bottom mirror))
    )
    (fp_text user "Author: Antmicro" (at -0.95 -4.169 180) (layer "B.Fab") hide
        (effects (font (size 0.7 0.7) (thickness 0.15)) (justify left bottom mirror))
    )
    (fp_text user "License: Apache-2.0" (at -0.95 -5.169 180) (layer "B.Fab") hide
        (effects (font (size 0.7 0.7) (thickness 0.15)) (justify left bottom mirror))
    )
    (fp_text user "${REFERENCE}" (at -0.95 -3.168 180) (layer "B.Fab") hide
        (effects (font (size 0.7 0.7) (thickness 0.15)) (justify left bottom mirror))
    )
    (fp_rect (start -0.93 0.47) (end 0.93 -0.47)
      (stroke (width 0.05) (type solid)) (fill none) (layer "B.CrtYd"))
    (fp_rect (start -0.5 0.25) (end 0.5 -0.25)
      (stroke (width 0.15) (type solid)) (fill none) (layer "B.Fab"))
    (pad "1" smd roundrect (at -0.485 0) (size 0.59 0.64) (layers "B.Cu" "B.Paste" "B.Mask") (roundrect_rratio 0.25)
      (net 119 "/Supply/~{INT}") (pintype "passive"))
    (pad "2" smd roundrect (at 0.485 0) (size 0.59 0.64) (layers "B.Cu" "B.Paste" "B.Mask") (roundrect_rratio 0.25)
      (net 859 "/Supply/OUT") (pintype "passive"))
  )
	(footprint "data-center-rdimm-ddr4-tester-footprints:SOT-753" (layer "B.Cu")
    (at 120.16 96.84)
    (property "Author" "Antmicro")
    (property "License" "Apache-2.0")
    (property "MPN" "SN74AHCT1G125DBVR")
    (property "Manufacturer" "Texas Instruments")
    (property "Sheetfile" "supply.kicad_sch")
    (property "Sheetname" "Supply")
    (attr smd)
    (fp_text reference "U23" (at -1.65 0.78 180) (layer "B.SilkS")
        (effects (font (size 0.7 0.7) (thickness 0.15)) (justify left bottom mirror))
    )
    (fp_text value "SN74AHCT1G125_SOT" (at 0 -2.9 180) (layer "B.Fab") hide
        (effects (font (size 0.7 0.7) (thickness 0.15)) (justify left bottom mirror))
    )
    (fp_text user "License: Apache-2.0" (at -1.651 -8.425 180) (layer "B.Fab") hide
        (effects (font (size 0.7 0.7) (thickness 0.15)) (justify left bottom mirror))
    )
    (fp_text user "${REFERENCE}" (at -1.651 -6.025 180) (layer "B.Fab") hide
        (effects (font (size 0.7 0.7) (thickness 0.15)) (justify left bottom mirror))
    )
    (fp_text user "Author: Antmicro" (at -1.651 -7.225 180) (layer "B.Fab") hide
        (effects (font (size 0.7 0.7) (thickness 0.15)) (justify left bottom mirror))
    )
    (fp_line (start -1.651 1) (end -1.651 0.701)
      (stroke (width 0.15) (type solid)) (layer "B.SilkS"))
    (fp_line (start -1.648 -1) (end -1.648 -0.677)
      (stroke (width 0.15) (type solid)) (layer "B.SilkS"))
    (fp_line (start -1.5 -1) (end -1.648 -1)
      (stroke (width 0.15) (type solid)) (layer "B.SilkS"))
    (fp_line (start -1.5 1) (end -1.651 1)
      (stroke (width 0.15) (type solid)) (layer "B.SilkS"))
    (fp_line (start 1.5 -0.998) (end 1.648 -0.998)
      (stroke (width 0.15) (type solid)) (layer "B.SilkS"))
    (fp_line (start 1.5 1) (end 1.648 1)
      (stroke (width 0.15) (type solid)) (layer "B.SilkS"))
    (fp_line (start 1.648 -0.998) (end 1.648 -0.699)
      (stroke (width 0.15) (type solid)) (layer "B.SilkS"))
    (fp_line (start 1.648 1) (end 1.648 0.677)
      (stroke (width 0.15) (type solid)) (layer "B.SilkS"))
    (fp_circle (center -1.5 -1.35) (end -1.46 -1.4)
      (stroke (width 0.15) (type solid)) (fill solid) (layer "B.SilkS"))
    (fp_rect (start -1.7 1.901) (end 1.699 -1.898)
      (stroke (width 0.05) (type solid)) (fill none) (layer "B.CrtYd"))
    (fp_line (start -1.526 -0.623) (end -1.526 0.875)
      (stroke (width 0.15) (type solid)) (layer "B.Fab"))
    (fp_line (start -1.526 -0.623) (end -1.351 -0.873)
      (stroke (width 0.15) (type solid)) (layer "B.Fab"))
    (fp_line (start -1.526 0.875) (end 1.523 0.875)
      (stroke (width 0.15) (type solid)) (layer "B.Fab"))
    (fp_line (start -1.351 -0.873) (end 1.523 -0.873)
      (stroke (width 0.15) (type solid)) (layer "B.Fab"))
    (fp_line (start 1.523 0.875) (end 1.523 -0.873)
      (stroke (width 0.15) (type solid)) (layer "B.Fab"))
    (pad "1" smd roundrect (at -0.951 -1.35) (size 0.6 1.05) (layers "B.Cu" "B.Paste" "B.Mask") (roundrect_rratio 0.25)
      (net 799 "FPGA_SLP_S4") (pinfunction "~{OE}") (pintype "input"))
    (pad "2" smd roundrect (at 0 -1.35) (size 0.6 1.05) (layers "B.Cu" "B.Paste" "B.Mask") (roundrect_rratio 0.25)
      (net 152 "/Supply/VCC_AUX_EN") (pinfunction "A") (pintype "input"))
    (pad "3" smd roundrect (at 0.949 -1.35) (size 0.6 1.05) (layers "B.Cu" "B.Paste" "B.Mask") (roundrect_rratio 0.25)
      (net 9 "GND") (pinfunction "GND") (pintype "power_in"))
    (pad "4" smd roundrect (at 0.949 1.351) (size 0.6 1.05) (layers "B.Cu" "B.Paste" "B.Mask") (roundrect_rratio 0.25)
      (net 794 "/Supply/SLP_S4") (pinfunction "Y") (pintype "output"))
    (pad "5" smd roundrect (at -0.951 1.351) (size 0.6 1.05) (layers "B.Cu" "B.Paste" "B.Mask") (roundrect_rratio 0.25)
      (net 307 "5V0_SYS") (pinfunction "V_{CC}") (pintype "power_in"))
  )
	(footprint "data-center-rdimm-ddr4-tester-footprints:C_0201" (layer "B.Cu")
    (at 173.65 94.65)
    (descr "Capacitor SMD 0201")
    (tags "capacitor SMD 0201")
    (property "Author" "Antmicro")
    (property "Dielectric" "")
    (property "License" "Apache-2.0")
    (property "MPN" "CC0201KRX6S5BB104")
    (property "Manufacturer" "Yaego")
    (property "Sheetfile" "fpga-power.kicad_sch")
    (property "Sheetname" "FPGA power")
    (property "Val" "100n")
    (property "Voltage" "")
    (property "ki_description" " ")
    (attr smd)
    (fp_text reference "C294" (at 1.36 1.1 180) (layer "B.SilkS")
        (effects (font (size 0.7 0.7) (thickness 0.15)) (justify left bottom mirror))
    )
    (fp_text value "C_100n_0201" (at 0 -1.4 180) (layer "B.Fab") hide
        (effects (font (size 0.7 0.7) (thickness 0.15)) (justify left bottom mirror))
    )
    (fp_text user "Author: Antmicro" (at -0.72 -5.4 180) (layer "B.Fab") hide
        (effects (font (size 0.7 0.7) (thickness 0.15)) (justify left bottom mirror))
    )
    (fp_text user "License: Apache-2.0" (at -0.72 -4.4 180) (layer "B.Fab") hide
        (effects (font (size 0.7 0.7) (thickness 0.15)) (justify left bottom mirror))
    )
    (fp_text user "${REFERENCE}" (at -0.72 -3.4 180) (layer "B.Fab") hide
        (effects (font (size 0.7 0.7) (thickness 0.15)) (justify left bottom mirror))
    )
    (fp_rect (start -0.72 0.38) (end 0.72 -0.38)
      (stroke (width 0.05) (type solid)) (fill none) (layer "B.CrtYd"))
    (fp_rect (start 0.3 -0.15) (end -0.301 0.149)
      (stroke (width 0.15) (type solid)) (fill none) (layer "B.Fab"))
    (pad "" smd roundrect (at -0.349 0.002) (size 0.318 0.36) (layers "B.Paste") (roundrect_rratio 0.25))
    (pad "" smd roundrect (at 0.341 0.002) (size 0.318 0.36) (layers "B.Paste") (roundrect_rratio 0.25))
    (pad "1" smd roundrect (at -0.321 0.002) (size 0.46 0.4) (layers "B.Cu" "B.Mask") (roundrect_rratio 0.25)
      (net 77 "VDDQ") (pintype "passive"))
    (pad "2" smd roundrect (at 0.32 0.002) (size 0.46 0.4) (layers "B.Cu" "B.Mask") (roundrect_rratio 0.25)
      (net 9 "GND") (pintype "passive"))
  )
	(footprint "data-center-rdimm-ddr4-tester-footprints:C_0201" (layer "B.Cu")
    (at 174.65 102.6 180)
    (descr "Capacitor SMD 0201")
    (tags "capacitor SMD 0201")
    (property "Author" "Antmicro")
    (property "Dielectric" "")
    (property "License" "Apache-2.0")
    (property "MPN" "CC0201KRX6S5BB104")
    (property "Manufacturer" "Yaego")
    (property "Sheetfile" "fpga-power.kicad_sch")
    (property "Sheetname" "FPGA power")
    (property "Val" "100n")
    (property "Voltage" "")
    (property "ki_description" " ")
    (attr smd)
    (fp_text reference "C84" (at -1.06 0.5) (layer "B.SilkS")
        (effects (font (size 0.7 0.7) (thickness 0.15)) (justify left bottom mirror))
    )
    (fp_text value "C_100n_0201" (at 0 -1.4) (layer "B.Fab") hide
        (effects (font (size 0.7 0.7) (thickness 0.15)) (justify left bottom mirror))
    )
    (fp_text user "${REFERENCE}" (at -0.72 -3.4) (layer "B.Fab") hide
        (effects (font (size 0.7 0.7) (thickness 0.15)) (justify left bottom mirror))
    )
    (fp_text user "License: Apache-2.0" (at -0.72 -4.4) (layer "B.Fab") hide
        (effects (font (size 0.7 0.7) (thickness 0.15)) (justify left bottom mirror))
    )
    (fp_text user "Author: Antmicro" (at -0.72 -5.4) (layer "B.Fab") hide
        (effects (font (size 0.7 0.7) (thickness 0.15)) (justify left bottom mirror))
    )
    (fp_rect (start -0.72 0.38) (end 0.72 -0.38)
      (stroke (width 0.05) (type solid)) (fill none) (layer "B.CrtYd"))
    (fp_rect (start 0.3 -0.15) (end -0.301 0.149)
      (stroke (width 0.15) (type solid)) (fill none) (layer "B.Fab"))
    (pad "" smd roundrect (at -0.349 0.002 180) (size 0.318 0.36) (layers "B.Paste") (roundrect_rratio 0.25))
    (pad "" smd roundrect (at 0.341 0.002 180) (size 0.318 0.36) (layers "B.Paste") (roundrect_rratio 0.25))
    (pad "1" smd roundrect (at -0.321 0.002 180) (size 0.46 0.4) (layers "B.Cu" "B.Mask") (roundrect_rratio 0.25)
      (net 143 "3V3_SYS") (pintype "passive"))
    (pad "2" smd roundrect (at 0.32 0.002 180) (size 0.46 0.4) (layers "B.Cu" "B.Mask") (roundrect_rratio 0.25)
      (net 9 "GND") (pintype "passive"))
  )
	(footprint "data-center-rdimm-ddr4-tester-footprints:R_0402_1005Metric" (layer "B.Cu")
    (at 132.575 108.815 90)
    (descr "Resistor SMD 0402")
    (tags "resistor SMD 0402")
    (property "Author" "Antmicro")
    (property "License" "Apache-2.0")
    (property "MPN" "CR0402-FX-1003GLF")
    (property "Manufacturer" "Bourns")
    (property "Sheetfile" "supply.kicad_sch")
    (property "Sheetname" "Supply")
    (property "Tolerance" "1%")
    (property "Val" "100k")
    (property "ki_description" "100k resistor in 0402 package with 1% tolerance")
    (attr smd)
    (fp_text reference "R192" (at -0.815 0.435 270) (layer "B.SilkS")
        (effects (font (size 0.7 0.7) (thickness 0.15)) (justify left bottom mirror))
    )
    (fp_text value "R_100k_0402" (at 0 -1.4 270) (layer "B.Fab") hide
        (effects (font (size 0.7 0.7) (thickness 0.15)) (justify left bottom mirror))
    )
    (fp_text user "License: Apache-2.0" (at -0.95 -5.169 270) (layer "B.Fab") hide
        (effects (font (size 0.7 0.7) (thickness 0.15)) (justify left bottom mirror))
    )
    (fp_text user "Author: Antmicro" (at -0.95 -4.169 270) (layer "B.Fab") hide
        (effects (font (size 0.7 0.7) (thickness 0.15)) (justify left bottom mirror))
    )
    (fp_text user "${REFERENCE}" (at -0.95 -3.168 270) (layer "B.Fab") hide
        (effects (font (size 0.7 0.7) (thickness 0.15)) (justify left bottom mirror))
    )
    (fp_rect (start -0.93 0.47) (end 0.93 -0.47)
      (stroke (width 0.05) (type solid)) (fill none) (layer "B.CrtYd"))
    (fp_rect (start -0.5 0.25) (end 0.5 -0.25)
      (stroke (width 0.15) (type solid)) (fill none) (layer "B.Fab"))
    (pad "1" smd roundrect (at -0.485 0 90) (size 0.59 0.64) (layers "B.Cu" "B.Paste" "B.Mask") (roundrect_rratio 0.25)
      (net 307 "5V0_SYS") (pintype "passive"))
    (pad "2" smd roundrect (at 0.485 0 90) (size 0.59 0.64) (layers "B.Cu" "B.Paste" "B.Mask") (roundrect_rratio 0.25)
      (net 583 "Net-(Q11-D)") (pintype "passive"))
  )
)
